(kicad_pcb
	(version 20260206)
	(generator "pcbnew")
	(generator_version "10.0")
	(general
		(thickness 1.6)
		(legacy_teardrops no)
	)
	(paper "A4")
	(title_block
		(title "Wiwynn_Tioga_Pass_MB.brd")
		(comment 1 "Tioga Pass / footprint 2254 of 4770 (U5D1), pads 1429-1533 of 3647")
	)
	(layers
		(0 "F.Cu" signal "TOP")
		(4 "In1.Cu" signal "L2GND")
		(6 "In2.Cu" signal "L3")
		(8 "In3.Cu" signal "L4GND")
		(10 "In4.Cu" signal "L5")
		(12 "In5.Cu" signal "L6GND")
		(14 "In6.Cu" signal "L7VCC")
		(16 "In7.Cu" signal "L8VCC")
		(18 "In8.Cu" signal "L9GND")
		(20 "In9.Cu" signal "L10")
		(22 "In10.Cu" signal "L11GND")
		(24 "In11.Cu" signal "L12")
		(26 "In12.Cu" signal "L13GND")
		(2 "B.Cu" signal "BOTTOM")
		(9 "F.Adhes" user "F.Adhesive")
		(11 "B.Adhes" user "B.Adhesive")
		(13 "F.Paste" user "Package Geometry/Pastemask Top")
		(15 "B.Paste" user "Package Geometry/Pastemask Bottom")
		(5 "F.SilkS" user "Ref Des/Silkscreen Top")
		(7 "B.SilkS" user "Ref Des/Silkscreen Bottom")
		(1 "F.Mask" user "Board Geometry/Soldermask Top")
		(3 "B.Mask" user "Board Geometry/Soldermask Bottom")
		(17 "Dwgs.User" user "User.Drawings")
		(19 "Cmts.User" user "User.Comments")
		(21 "Eco1.User" user "User.Eco1")
		(23 "Eco2.User" user "User.Eco2")
		(25 "Edge.Cuts" user "Board Geometry/Outline")
		(27 "Margin" user)
		(31 "F.CrtYd" user "Package Geometry/Place Bound Top")
		(29 "B.CrtYd" user "Package Geometry/Place Bound Bottom")
		(35 "F.Fab" user "Ref Des/Assembly Top")
		(33 "B.Fab" user "Ref Des/Assembly Bottom")
	)
	(footprint ""
		(layer "F.Cu")
		(at 270.000222 -76.550012 180)
		(property "Reference" "U5D1"
			(at 19.124422 31.601918 0)
			(unlocked yes)
			(layer "F.SilkS")
			(effects
				(font
					(size 0.7874 0.5842)
					(thickness 0.1524)
				)
			)
		)
		(property "Value" ""
			(at 0 0 180)
			(layer "F.Fab")
			(effects
				(font
					(size 1.27 1.27)
				)
			)
		)
		(duplicate_pad_numbers_are_jumpers no)
		(pad "CF7" smd circle
			(at -32.099504 7.091172)
			(size 0.4318 0.4318)
			(layers "F.Cu" "F.Mask" "F.Paste")
			(net "P3E_CPU0_PE2_SS_RXP<5>")
		)
		(pad "CF9" smd circle
			(at -30.382464 7.091172)
			(size 0.4318 0.4318)
			(layers "F.Cu" "F.Mask" "F.Paste")
			(net "GND")
		)
		(pad "CF11" smd circle
			(at -28.665424 7.091172)
			(size 0.4318 0.4318)
			(layers "F.Cu" "F.Mask" "F.Paste")
			(net "TP_CPU0_UPI2_RSVD_DJ20")
		)
		(pad "CF13" smd circle
			(at -26.948384 7.091172)
			(size 0.4318 0.4318)
			(layers "F.Cu" "F.Mask" "F.Paste")
			(net "TP_CPU0_UPI2_RSVD_DH19")
		)
		(pad "CF15" smd circle
			(at -25.231598 7.091172)
			(size 0.4318 0.4318)
			(layers "F.Cu" "F.Mask" "F.Paste")
			(net "GND")
		)
		(pad "CF17" smd circle
			(at -23.514558 7.091172)
			(size 0.4318 0.4318)
			(layers "F.Cu" "F.Mask" "F.Paste")
			(net "GND")
		)
		(pad "CF19" smd circle
			(at -21.797518 7.091172)
			(size 0.4318 0.4318)
			(layers "F.Cu" "F.Mask" "F.Paste")
			(net "PVCCMCP_CPU0")
		)
		(pad "CF21" smd circle
			(at -20.080478 7.091172)
			(size 0.4318 0.4318)
			(layers "F.Cu" "F.Mask" "F.Paste")
			(net "PVCCMCP_CPU0")
		)
		(pad "CF23" smd circle
			(at -18.363438 7.091172)
			(size 0.4318 0.4318)
			(layers "F.Cu" "F.Mask" "F.Paste")
			(net "PVCCMCP_CPU0")
		)
		(pad "CF25" smd circle
			(at -16.646398 7.091172)
			(size 0.4318 0.4318)
			(layers "F.Cu" "F.Mask" "F.Paste")
			(net "RST_CD_CPU0_POR_N")
		)
		(pad "CF27" smd circle
			(at -14.929612 7.091172)
			(size 0.4318 0.4318)
			(layers "F.Cu" "F.Mask" "F.Paste")
			(net "PVCCIO_CPU0")
		)
		(pad "CF61" smd circle
			(at 15.787878 5.291074)
			(size 0.4318 0.4318)
			(layers "F.Cu" "F.Mask" "F.Paste")
			(net "PVCCIN_CPU0")
		)
		(pad "CF63" smd circle
			(at 17.504918 5.291074)
			(size 0.4318 0.4318)
			(layers "F.Cu" "F.Mask" "F.Paste")
			(net "GND")
		)
		(pad "CF65" smd circle
			(at 19.221958 5.291074)
			(size 0.4318 0.4318)
			(layers "F.Cu" "F.Mask" "F.Paste")
			(net "PVSA_CPU0")
		)
		(pad "CF67" smd circle
			(at 20.938998 5.291074)
			(size 0.4318 0.4318)
			(layers "F.Cu" "F.Mask" "F.Paste")
			(net "PVSA_CPU0")
		)
		(pad "CF69" smd circle
			(at 22.656038 5.291074)
			(size 0.4318 0.4318)
			(layers "F.Cu" "F.Mask" "F.Paste")
			(net "GND")
		)
		(pad "CF71" smd circle
			(at 24.373078 5.291074)
			(size 0.4318 0.4318)
			(layers "F.Cu" "F.Mask" "F.Paste")
			(net "GND")
		)
		(pad "CF73" smd circle
			(at 26.090118 5.291074)
			(size 0.4318 0.4318)
			(layers "F.Cu" "F.Mask" "F.Paste")
			(net "PVSA_CPU0")
		)
		(pad "CF75" smd circle
			(at 27.806904 5.291074)
			(size 0.4318 0.4318)
			(layers "F.Cu" "F.Mask" "F.Paste")
			(net "PVSA_CPU0")
		)
		(pad "CF77" smd circle
			(at 29.523944 5.291074)
			(size 0.4318 0.4318)
			(layers "F.Cu" "F.Mask" "F.Paste")
			(net "GND")
		)
		(pad "CF79" smd circle
			(at 31.240984 5.291074)
			(size 0.4318 0.4318)
			(layers "F.Cu" "F.Mask" "F.Paste")
			(net "TP_CPU0_RSVD_101")
		)
		(pad "CF81" smd circle
			(at 32.958024 5.291074)
			(size 0.4318 0.4318)
			(layers "F.Cu" "F.Mask" "F.Paste")
			(net "TP_CPU0_RSVD_100")
		)
		(pad "CF83" smd circle
			(at 34.675064 5.291074)
			(size 0.4318 0.4318)
			(layers "F.Cu" "F.Mask" "F.Paste")
			(net "GND")
		)
		(pad "CF85" smd custom
			(at 36.392104 5.291074 270)
			(size 0.10795 0.10795)
			(layers "F.Cu" "F.Mask" "F.Paste")
			(net "PVCCIN_CPU0")
			(options
				(clearance outline)
				(anchor circle)
			)
			(primitives
				(gr_poly
					(pts
						(arc
							(start 0.2159 -0.0381)
							(mid 0 -0.254)
							(end -0.2159 -0.0381)
						)
						(arc
							(start -0.2159 0.0381)
							(mid 0 0.254)
							(end 0.2159 0.0381)
						)
					)
					(width 0)
					(fill yes)
				)
			)
		)
		(pad "CG2" smd custom
			(at -36.392104 7.586726 90)
			(size 0.10795 0.10795)
			(layers "F.Cu" "F.Mask" "F.Paste")
			(net "P3E_CPU0_PE2_SS_TXN<6>")
			(options
				(clearance outline)
				(anchor circle)
			)
			(primitives
				(gr_poly
					(pts
						(arc
							(start 0.2159 -0.0381)
							(mid 0 -0.254)
							(end -0.2159 -0.0381)
						)
						(arc
							(start -0.2159 0.0381)
							(mid 0 0.254)
							(end 0.2159 0.0381)
						)
					)
					(width 0)
					(fill yes)
				)
			)
		)
		(pad "CG4" smd circle
			(at -34.675064 7.586726)
			(size 0.4318 0.4318)
			(layers "F.Cu" "F.Mask" "F.Paste")
			(net "DMI_CPU0_PCH_TX_DN<0>")
		)
		(pad "CG6" smd circle
			(at -32.958024 7.586726)
			(size 0.4318 0.4318)
			(layers "F.Cu" "F.Mask" "F.Paste")
			(net "GND")
		)
		(pad "CG8" smd circle
			(at -31.240984 7.586726)
			(size 0.4318 0.4318)
			(layers "F.Cu" "F.Mask" "F.Paste")
			(net "P3E_CPU0_PE2_SS_RXN<5>")
		)
		(pad "CG10" smd circle
			(at -29.523944 7.586726)
			(size 0.4318 0.4318)
			(layers "F.Cu" "F.Mask" "F.Paste")
			(net "TP_CPU0_RSVD_99")
		)
		(pad "CG12" smd circle
			(at -27.806904 7.586726)
			(size 0.4318 0.4318)
			(layers "F.Cu" "F.Mask" "F.Paste")
			(net "TP_CPU0_UPI2_RSVD_DJ18")
		)
		(pad "CG14" smd circle
			(at -26.090118 7.586726)
			(size 0.4318 0.4318)
			(layers "F.Cu" "F.Mask" "F.Paste")
			(net "PVCCIO_CPU0")
		)
		(pad "CG16" smd circle
			(at -24.373078 7.586726)
			(size 0.4318 0.4318)
			(layers "F.Cu" "F.Mask" "F.Paste")
			(net "GND")
		)
		(pad "CG18" smd circle
			(at -22.656038 7.586726)
			(size 0.4318 0.4318)
			(layers "F.Cu" "F.Mask" "F.Paste")
			(net "GND")
		)
		(pad "CG20" smd circle
			(at -20.938998 7.586726)
			(size 0.4318 0.4318)
			(layers "F.Cu" "F.Mask" "F.Paste")
			(net "PVCCMCP_CPU0")
		)
		(pad "CG22" smd circle
			(at -19.221958 7.586726)
			(size 0.4318 0.4318)
			(layers "F.Cu" "F.Mask" "F.Paste")
			(net "GND")
		)
		(pad "CG24" smd circle
			(at -17.504918 7.586726)
			(size 0.4318 0.4318)
			(layers "F.Cu" "F.Mask" "F.Paste")
			(net "TP_CPU0_RSVD_97")
		)
		(pad "CG26" smd circle
			(at -15.787878 7.586726)
			(size 0.4318 0.4318)
			(layers "F.Cu" "F.Mask" "F.Paste")
			(net "PVCCMCP_CPU0")
		)
		(pad "CG60" smd circle
			(at 14.929612 5.786628)
			(size 0.508 0.508)
			(layers "F.Cu" "F.Mask" "F.Paste")
			(net "PVCCIN_CPU0")
		)
		(pad "CG62" smd circle
			(at 16.646398 5.786628)
			(size 0.4318 0.4318)
			(layers "F.Cu" "F.Mask" "F.Paste")
			(net "GND")
		)
		(pad "CG64" smd circle
			(at 18.363438 5.786628)
			(size 0.4318 0.4318)
			(layers "F.Cu" "F.Mask" "F.Paste")
			(net "PVSA_CPU0")
		)
		(pad "CG66" smd circle
			(at 20.080478 5.786628)
			(size 0.4318 0.4318)
			(layers "F.Cu" "F.Mask" "F.Paste")
			(net "PVSA_CPU0")
		)
		(pad "CG68" smd circle
			(at 21.797518 5.786628)
			(size 0.4318 0.4318)
			(layers "F.Cu" "F.Mask" "F.Paste")
			(net "GND")
		)
		(pad "CG70" smd circle
			(at 23.514558 5.786628)
			(size 0.4318 0.4318)
			(layers "F.Cu" "F.Mask" "F.Paste")
			(net "M_F_DQS_DP<17>")
		)
		(pad "CG72" smd circle
			(at 25.231598 5.786628)
			(size 0.4318 0.4318)
			(layers "F.Cu" "F.Mask" "F.Paste")
			(net "GND")
		)
		(pad "CG74" smd circle
			(at 26.948384 5.786628)
			(size 0.4318 0.4318)
			(layers "F.Cu" "F.Mask" "F.Paste")
			(net "PVSA_CPU0")
		)
		(pad "CG76" smd circle
			(at 28.665424 5.786628)
			(size 0.4318 0.4318)
			(layers "F.Cu" "F.Mask" "F.Paste")
			(net "VSENSE_PVSA_CPU0_SKT_VRTN")
		)
		(pad "CG78" smd circle
			(at 30.382464 5.786628)
			(size 0.4318 0.4318)
			(layers "F.Cu" "F.Mask" "F.Paste")
			(net "TP_CPU0_RSVD_95")
		)
		(pad "CG80" smd circle
			(at 32.099504 5.786628)
			(size 0.4318 0.4318)
			(layers "F.Cu" "F.Mask" "F.Paste")
			(net "GND")
		)
		(pad "CG82" smd circle
			(at 33.816544 5.786628)
			(size 0.4318 0.4318)
			(layers "F.Cu" "F.Mask" "F.Paste")
			(net "TP_CPU0_RSVD_94")
		)
		(pad "CG84" smd circle
			(at 35.533584 5.786628)
			(size 0.4318 0.4318)
			(layers "F.Cu" "F.Mask" "F.Paste")
			(net "PVCCIN_CPU0")
		)
		(pad "CH1" smd custom
			(at -37.250624 8.081772 90)
			(size 0.10795 0.10795)
			(layers "F.Cu" "F.Mask" "F.Paste")
			(net "GND")
			(options
				(clearance outline)
				(anchor circle)
			)
			(primitives
				(gr_poly
					(pts
						(arc
							(start 0.2159 -0.0381)
							(mid 0 -0.254)
							(end -0.2159 -0.0381)
						)
						(arc
							(start -0.2159 0.0381)
							(mid 0 0.254)
							(end 0.2159 0.0381)
						)
					)
					(width 0)
					(fill yes)
				)
			)
		)
		(pad "CH3" smd circle
			(at -35.533584 8.081772)
			(size 0.4318 0.4318)
			(layers "F.Cu" "F.Mask" "F.Paste")
			(net "GND")
		)
		(pad "CH5" smd circle
			(at -33.816544 8.081772)
			(size 0.4318 0.4318)
			(layers "F.Cu" "F.Mask" "F.Paste")
			(net "DMI_CPU0_PCH_TX_DP<0>")
		)
		(pad "CH7" smd circle
			(at -32.099504 8.081772)
			(size 0.4318 0.4318)
			(layers "F.Cu" "F.Mask" "F.Paste")
			(net "P3E_CPU0_PE2_SS_RXP<4>")
		)
		(pad "CH9" smd circle
			(at -30.382464 8.081772)
			(size 0.4318 0.4318)
			(layers "F.Cu" "F.Mask" "F.Paste")
			(net "PVCCIO_CPU0")
		)
		(pad "CH11" smd circle
			(at -28.665424 8.081772)
			(size 0.4318 0.4318)
			(layers "F.Cu" "F.Mask" "F.Paste")
			(net "TP_CPU0_UPI2_RSVD_DG20")
		)
		(pad "CH13" smd circle
			(at -26.948384 8.081772)
			(size 0.4318 0.4318)
			(layers "F.Cu" "F.Mask" "F.Paste")
			(net "TP_CPU0_UPI2_RSVD_DH17")
		)
		(pad "CH15" smd circle
			(at -25.231598 8.081772)
			(size 0.4318 0.4318)
			(layers "F.Cu" "F.Mask" "F.Paste")
			(net "GND")
		)
		(pad "CH17" smd circle
			(at -23.514558 8.081772)
			(size 0.4318 0.4318)
			(layers "F.Cu" "F.Mask" "F.Paste")
			(net "GND")
		)
		(pad "CH19" smd circle
			(at -21.797518 8.081772)
			(size 0.4318 0.4318)
			(layers "F.Cu" "F.Mask" "F.Paste")
			(net "GND")
		)
		(pad "CH21" smd circle
			(at -20.080478 8.081772)
			(size 0.4318 0.4318)
			(layers "F.Cu" "F.Mask" "F.Paste")
			(net "PVCCMCP_CPU0")
		)
		(pad "CH23" smd circle
			(at -18.363438 8.081772)
			(size 0.4318 0.4318)
			(layers "F.Cu" "F.Mask" "F.Paste")
			(net "PVCCMCP_CPU0")
		)
		(pad "CH25" smd circle
			(at -16.646398 8.081772)
			(size 0.4318 0.4318)
			(layers "F.Cu" "F.Mask" "F.Paste")
			(net "TP_CPU0_RSVD_91")
		)
		(pad "CH27" smd circle
			(at -14.929612 8.081772)
			(size 0.4318 0.4318)
			(layers "F.Cu" "F.Mask" "F.Paste")
			(net "PVCCIO_CPU0")
		)
		(pad "CH61" smd circle
			(at 15.787878 6.281928)
			(size 0.4318 0.4318)
			(layers "F.Cu" "F.Mask" "F.Paste")
			(net "PVCCIN_CPU0")
		)
		(pad "CH63" smd circle
			(at 17.504918 6.281928)
			(size 0.4318 0.4318)
			(layers "F.Cu" "F.Mask" "F.Paste")
			(net "GND")
		)
		(pad "CH65" smd circle
			(at 19.221958 6.281928)
			(size 0.4318 0.4318)
			(layers "F.Cu" "F.Mask" "F.Paste")
			(net "PVSA_CPU0")
		)
		(pad "CH67" smd circle
			(at 20.938998 6.281928)
			(size 0.4318 0.4318)
			(layers "F.Cu" "F.Mask" "F.Paste")
			(net "GND")
		)
		(pad "CH69" smd circle
			(at 22.656038 6.281928)
			(size 0.4318 0.4318)
			(layers "F.Cu" "F.Mask" "F.Paste")
			(net "M_F_ECC<6>")
		)
		(pad "CH71" smd circle
			(at 24.373078 6.281928)
			(size 0.4318 0.4318)
			(layers "F.Cu" "F.Mask" "F.Paste")
			(net "M_F_ECC<0>")
		)
		(pad "CH73" smd circle
			(at 26.090118 6.281928)
			(size 0.4318 0.4318)
			(layers "F.Cu" "F.Mask" "F.Paste")
			(net "GND")
		)
		(pad "CH75" smd circle
			(at 27.806904 6.281928)
			(size 0.4318 0.4318)
			(layers "F.Cu" "F.Mask" "F.Paste")
			(net "PVSA_CPU0")
		)
		(pad "CH77" smd circle
			(at 29.523944 6.281928)
			(size 0.4318 0.4318)
			(layers "F.Cu" "F.Mask" "F.Paste")
			(net "TP_CPU0_RSVD_90")
		)
		(pad "CH79" smd circle
			(at 31.240984 6.281928)
			(size 0.4318 0.4318)
			(layers "F.Cu" "F.Mask" "F.Paste")
			(net "GND")
		)
		(pad "CH81" smd circle
			(at 32.958024 6.281928)
			(size 0.4318 0.4318)
			(layers "F.Cu" "F.Mask" "F.Paste")
			(net "GND")
		)
		(pad "CH83" smd circle
			(at 34.675064 6.281928)
			(size 0.4318 0.4318)
			(layers "F.Cu" "F.Mask" "F.Paste")
			(net "GND")
		)
		(pad "CH85" smd custom
			(at 36.392104 6.281928 270)
			(size 0.10795 0.10795)
			(layers "F.Cu" "F.Mask" "F.Paste")
			(net "PVCCIN_CPU0")
			(options
				(clearance outline)
				(anchor circle)
			)
			(primitives
				(gr_poly
					(pts
						(arc
							(start 0.2159 -0.0381)
							(mid 0 -0.254)
							(end -0.2159 -0.0381)
						)
						(arc
							(start -0.2159 0.0381)
							(mid 0 0.254)
							(end 0.2159 0.0381)
						)
					)
					(width 0)
					(fill yes)
				)
			)
		)
		(pad "CJ2" smd circle
			(at -36.392104 8.577326)
			(size 0.4318 0.4318)
			(layers "F.Cu" "F.Mask" "F.Paste")
			(net "GND")
		)
		(pad "CJ4" smd circle
			(at -34.675064 8.577326)
			(size 0.4318 0.4318)
			(layers "F.Cu" "F.Mask" "F.Paste")
			(net "DMI_CPU0_PCH_TX_DN<1>")
		)
		(pad "CJ6" smd circle
			(at -32.958024 8.577326)
			(size 0.4318 0.4318)
			(layers "F.Cu" "F.Mask" "F.Paste")
			(net "GND")
		)
		(pad "CJ8" smd circle
			(at -31.240984 8.577326)
			(size 0.4318 0.4318)
			(layers "F.Cu" "F.Mask" "F.Paste")
			(net "GND")
		)
		(pad "CJ10" smd circle
			(at -29.523944 8.577326)
			(size 0.4318 0.4318)
			(layers "F.Cu" "F.Mask" "F.Paste")
			(net "GND")
		)
		(pad "CJ12" smd circle
			(at -27.806904 8.577326)
			(size 0.4318 0.4318)
			(layers "F.Cu" "F.Mask" "F.Paste")
			(net "GND")
		)
		(pad "CJ14" smd circle
			(at -26.090118 8.577326)
			(size 0.4318 0.4318)
			(layers "F.Cu" "F.Mask" "F.Paste")
			(net "TP_CPU0_UPI2_RSVD_DK17")
		)
		(pad "CJ16" smd circle
			(at -24.373078 8.577326)
			(size 0.4318 0.4318)
			(layers "F.Cu" "F.Mask" "F.Paste")
			(net "GND")
		)
		(pad "CJ18" smd circle
			(at -22.656038 8.577326)
			(size 0.4318 0.4318)
			(layers "F.Cu" "F.Mask" "F.Paste")
			(net "GND")
		)
		(pad "CJ20" smd circle
			(at -20.938998 8.577326)
			(size 0.4318 0.4318)
			(layers "F.Cu" "F.Mask" "F.Paste")
			(net "PVCCMCP_CPU0")
		)
		(pad "CJ22" smd circle
			(at -19.221958 8.577326)
			(size 0.4318 0.4318)
			(layers "F.Cu" "F.Mask" "F.Paste")
			(net "PVCCMCP_CPU0")
		)
		(pad "CJ24" smd circle
			(at -17.504918 8.577326)
			(size 0.4318 0.4318)
			(layers "F.Cu" "F.Mask" "F.Paste")
			(net "PVCCMCP_CPU0")
		)
		(pad "CJ26" smd circle
			(at -15.787878 8.577326)
			(size 0.4318 0.4318)
			(layers "F.Cu" "F.Mask" "F.Paste")
			(net "PVCCMCP_CPU0")
		)
		(pad "CJ28" smd circle
			(at -14.071092 8.577326)
			(size 0.4318 0.4318)
			(layers "F.Cu" "F.Mask" "F.Paste")
			(net "PVCCIO_CPU0")
		)
		(pad "CJ60" smd circle
			(at 14.929612 6.777228)
			(size 0.508 0.508)
			(layers "F.Cu" "F.Mask" "F.Paste")
			(net "PVCCIN_CPU0")
		)
		(pad "CJ62" smd circle
			(at 16.646398 6.777228)
			(size 0.4318 0.4318)
			(layers "F.Cu" "F.Mask" "F.Paste")
			(net "GND")
		)
		(pad "CJ64" smd circle
			(at 18.363438 6.777228)
			(size 0.4318 0.4318)
			(layers "F.Cu" "F.Mask" "F.Paste")
			(net "PVSA_CPU0")
		)
		(pad "CJ66" smd circle
			(at 20.080478 6.777228)
			(size 0.4318 0.4318)
			(layers "F.Cu" "F.Mask" "F.Paste")
			(net "PVSA_CPU0")
		)
		(pad "CJ68" smd circle
			(at 21.797518 6.777228)
			(size 0.4318 0.4318)
			(layers "F.Cu" "F.Mask" "F.Paste")
			(net "M_F_ECC<2>")
		)
		(pad "CJ70" smd circle
			(at 23.514558 6.777228)
			(size 0.4318 0.4318)
			(layers "F.Cu" "F.Mask" "F.Paste")
			(net "M_F_DQS_DN<17>")
		)
		(pad "CJ72" smd circle
			(at 25.231598 6.777228)
			(size 0.4318 0.4318)
			(layers "F.Cu" "F.Mask" "F.Paste")
			(net "M_F_ECC<4>")
		)
		(pad "CJ74" smd circle
			(at 26.948384 6.777228)
			(size 0.4318 0.4318)
			(layers "F.Cu" "F.Mask" "F.Paste")
			(net "GND")
		)
		(pad "CJ76" smd circle
			(at 28.665424 6.777228)
			(size 0.4318 0.4318)
			(layers "F.Cu" "F.Mask" "F.Paste")
			(net "GND")
		)
		(pad "CJ78" smd circle
			(at 30.382464 6.777228)
			(size 0.4318 0.4318)
			(layers "F.Cu" "F.Mask" "F.Paste")
			(net "GND")
		)
		(pad "CJ80" smd circle
			(at 32.099504 6.777228)
			(size 0.4318 0.4318)
			(layers "F.Cu" "F.Mask" "F.Paste")
			(net "M_E_DQ<5>")
		)
		(pad "CJ82" smd circle
			(at 33.816544 6.777228)
			(size 0.4318 0.4318)
			(layers "F.Cu" "F.Mask" "F.Paste")
			(net "GND")
		)
		(pad "CJ84" smd circle
			(at 35.533584 6.777228)
			(size 0.4318 0.4318)
			(layers "F.Cu" "F.Mask" "F.Paste")
			(net "GND")
		)
		(pad "CJ86" smd custom
			(at 37.250624 6.777228 270)
			(size 0.10795 0.10795)
			(layers "F.Cu" "F.Mask" "F.Paste")
			(net "GND")
			(options
				(clearance outline)
				(anchor circle)
			)
			(primitives
				(gr_poly
					(pts
						(arc
							(start 0.2159 -0.0381)
							(mid 0 -0.254)
							(end -0.2159 -0.0381)
						)
						(arc
							(start -0.2159 0.0381)
							(mid 0 0.254)
							(end 0.2159 0.0381)
						)
					)
					(width 0)
					(fill yes)
				)
			)
		)
	)
)
